(kicad_pcb
	(version 20260206)
	(generator "pcbnew")
	(generator_version "10.0")
	(general
		(thickness 1.6)
		(legacy_teardrops no)
	)
	(paper "A4")
	(title_block
		(title "03242023_DA0F0TMBIJ0_F0T_Motherboard_J_brd_V01_OCP.brd")
		(comment 1 "Grand Teton / footprints 3211-3215 of 6105")
	)
	(layers
		(0 "F.Cu" signal "TOP")
		(4 "In1.Cu" signal "GND")
		(6 "In2.Cu" signal "IN1")
		(8 "In3.Cu" signal "GND1")
		(10 "In4.Cu" signal "IN2")
		(12 "In5.Cu" signal "GND2")
		(14 "In6.Cu" signal "IN3")
		(16 "In7.Cu" signal "GND3")
		(18 "In8.Cu" signal "VCC")
		(20 "In9.Cu" signal "VCC1")
		(22 "In10.Cu" signal "GND4")
		(24 "In11.Cu" signal "IN4")
		(26 "In12.Cu" signal "GND5")
		(28 "In13.Cu" signal "IN5")
		(30 "In14.Cu" signal "GND6")
		(32 "In15.Cu" signal "IN6")
		(34 "In16.Cu" signal "GND7")
		(2 "B.Cu" signal "BOTTOM")
		(9 "F.Adhes" user "F.Adhesive")
		(11 "B.Adhes" user "B.Adhesive")
		(13 "F.Paste" user "Package Geometry/Pastemask Top")
		(15 "B.Paste" user "Package Geometry/Pastemask Bottom")
		(5 "F.SilkS" user "Ref Des/Silkscreen Top")
		(7 "B.SilkS" user "Ref Des/Silkscreen Bottom")
		(1 "F.Mask" user "Board Geometry/Soldermask Top")
		(3 "B.Mask" user "Board Geometry/Soldermask Bottom")
		(17 "Dwgs.User" user "User.Drawings")
		(19 "Cmts.User" user "User.Comments")
		(21 "Eco1.User" user "User.Eco1")
		(23 "Eco2.User" user "User.Eco2")
		(25 "Edge.Cuts" user "Board Geometry/Outline")
		(27 "Margin" user)
		(31 "F.CrtYd" user "Package Geometry/Place Bound Top")
		(29 "B.CrtYd" user "Package Geometry/Place Bound Bottom")
		(35 "F.Fab" user "Ref Des/Assembly Top")
		(33 "B.Fab" user "Ref Des/Assembly Bottom")
	)
	(footprint ""
		(layer "F.Cu")
		(at 79.356458 -20.694142)
		(property "Reference" "PU201"
			(at -9.250172 -0.290322 0)
			(unlocked yes)
			(layer "F.SilkS")
			(effects
				(font
					(size 0.7874 0.5842)
					(thickness 0.1524)
				)
				(justify left)
			)
		)
		(property "Value" ""
			(at 0 0 0)
			(layer "F.Fab")
			(effects
				(font
					(size 1.27 1.27)
				)
			)
		)
		(duplicate_pad_numbers_are_jumpers no)
		(fp_line
			(start -1.774952 -1.039876)
			(end -1.774952 1.039876)
			(stroke
				(width 0.1524)
				(type default)
			)
			(layer "F.SilkS")
		)
		(fp_line
			(start -1.774952 1.039876)
			(end 1.774952 1.039876)
			(stroke
				(width 0.1524)
				(type default)
			)
			(layer "F.SilkS")
		)
		(fp_line
			(start 1.774952 -1.039876)
			(end -1.774952 -1.039876)
			(stroke
				(width 0.1524)
				(type default)
			)
			(layer "F.SilkS")
		)
		(fp_line
			(start 1.774952 1.039876)
			(end 1.774952 -1.039876)
			(stroke
				(width 0.1524)
				(type default)
			)
			(layer "F.SilkS")
		)
		(fp_poly
			(pts
				(xy -1.769872 -1.039876) (xy -1.769872 -0.249936) (xy -2.531872 -0.249936) (xy -2.531872 -1.801876)
				(xy -0.999998 -1.801876) (xy -0.999998 -1.039876)
			)
			(stroke
				(width 0)
				(type default)
			)
			(fill yes)
			(layer "F.SilkS")
		)
		(fp_line
			(start -1.769872 -1.039876)
			(end -1.769872 1.039876)
			(stroke
				(width 0.1)
				(type default)
			)
			(layer "F.Fab")
		)
		(fp_line
			(start -1.769872 1.039876)
			(end 1.769872 1.039876)
			(stroke
				(width 0.1)
				(type default)
			)
			(layer "F.Fab")
		)
		(fp_line
			(start 1.769872 -1.039876)
			(end -1.769872 -1.039876)
			(stroke
				(width 0.1)
				(type default)
			)
			(layer "F.Fab")
		)
		(fp_line
			(start 1.769872 1.039876)
			(end 1.769872 -1.039876)
			(stroke
				(width 0.1)
				(type default)
			)
			(layer "F.Fab")
		)
		(fp_poly
			(pts
				(xy -1.769872 -1.039876) (xy -0.999998 -1.039876) (xy -0.999998 -1.801876) (xy -2.531872 -1.801876)
				(xy -2.531872 -0.249936) (xy -1.769872 -0.249936)
			)
			(stroke
				(width 0)
				(type default)
			)
			(fill yes)
			(layer "F.Fab")
		)
		(pad "A1" smd circle
			(at -1.500124 -0.750062)
			(size 0.2286 0.2286)
			(layers "F.Cu" "F.Mask" "F.Paste")
			(net "P12V_OCP_SENSE_2")
		)
		(pad "A2" smd circle
			(at -0.999998 -0.750062)
			(size 0.2286 0.2286)
			(layers "F.Cu" "F.Mask" "F.Paste")
			(net "P12V_OCP_VCC_2")
		)
		(pad "A3" smd circle
			(at -0.499872 -0.750062)
			(size 0.2286 0.2286)
			(layers "F.Cu" "F.Mask" "F.Paste")
			(net "P12V_AUX")
		)
		(pad "A4" smd circle
			(at 0 -0.750062)
			(size 0.2286 0.2286)
			(layers "F.Cu" "F.Mask" "F.Paste")
			(net "P12V_OCP_V3_2")
		)
		(pad "A5" smd circle
			(at 0.499872 -0.750062)
			(size 0.2286 0.2286)
			(layers "F.Cu" "F.Mask" "F.Paste")
			(net "P12V_AUX")
		)
		(pad "A6" smd circle
			(at 0.999998 -0.750062)
			(size 0.2286 0.2286)
			(layers "F.Cu" "F.Mask" "F.Paste")
			(net "P12V_OCP_GATE_2")
		)
		(pad "A7" smd circle
			(at 1.500124 -0.750062)
			(size 0.2286 0.2286)
			(layers "F.Cu" "F.Mask" "F.Paste")
			(net "GND")
		)
		(pad "B1" smd circle
			(at -1.500124 -0.249936)
			(size 0.2286 0.2286)
			(layers "F.Cu" "F.Mask" "F.Paste")
			(net "P12V_OCP_CB_2")
		)
		(pad "B2" smd circle
			(at -0.999998 -0.249936)
			(size 0.2286 0.2286)
			(layers "F.Cu" "F.Mask" "F.Paste")
			(net "GND")
		)
		(pad "B3" smd circle
			(at -0.499872 -0.249936)
			(size 0.2286 0.2286)
			(layers "F.Cu" "F.Mask" "F.Paste")
			(net "P12V_AUX")
		)
		(pad "B4" smd circle
			(at 0 -0.249936)
			(size 0.2286 0.2286)
			(layers "F.Cu" "F.Mask" "F.Paste")
			(net "P12V_OCP_V3_2")
		)
		(pad "B5" smd circle
			(at 0.499872 -0.249936)
			(size 0.2286 0.2286)
			(layers "F.Cu" "F.Mask" "F.Paste")
			(net "P12V_AUX")
		)
		(pad "B6" smd circle
			(at 0.999998 -0.249936)
			(size 0.2286 0.2286)
			(layers "F.Cu" "F.Mask" "F.Paste")
			(net "P12V_OCP_V3_2")
		)
		(pad "B7" smd circle
			(at 1.500124 -0.249936)
			(size 0.2286 0.2286)
			(layers "F.Cu" "F.Mask" "F.Paste")
			(net "GND")
		)
		(pad "C1" smd circle
			(at -1.500124 0.249936)
			(size 0.2286 0.2286)
			(layers "F.Cu" "F.Mask" "F.Paste")
			(net "GND")
		)
		(pad "C2" smd circle
			(at -0.999998 0.249936)
			(size 0.2286 0.2286)
			(layers "F.Cu" "F.Mask" "F.Paste")
			(net "GND")
		)
		(pad "C3" smd circle
			(at -0.499872 0.249936)
			(size 0.2286 0.2286)
			(layers "F.Cu" "F.Mask" "F.Paste")
			(net "P12V_AUX")
		)
		(pad "C4" smd circle
			(at 0 0.249936)
			(size 0.2286 0.2286)
			(layers "F.Cu" "F.Mask" "F.Paste")
			(net "P12V_OCP_V3_2")
		)
		(pad "C5" smd circle
			(at 0.499872 0.249936)
			(size 0.2286 0.2286)
			(layers "F.Cu" "F.Mask" "F.Paste")
			(net "P12V_AUX")
		)
		(pad "C6" smd circle
			(at 0.999998 0.249936)
			(size 0.2286 0.2286)
			(layers "F.Cu" "F.Mask" "F.Paste")
			(net "P12V_OCP_V3_2")
		)
		(pad "C7" smd circle
			(at 1.500124 0.249936)
			(size 0.2286 0.2286)
			(layers "F.Cu" "F.Mask" "F.Paste")
			(net "P12V_OCP_FAULT_2")
		)
		(pad "D1" smd circle
			(at -1.500124 0.750062)
			(size 0.2286 0.2286)
			(layers "F.Cu" "F.Mask" "F.Paste")
			(net "P12V_OCP_REG_2")
		)
		(pad "D2" smd circle
			(at -0.999998 0.750062)
			(size 0.2286 0.2286)
			(layers "F.Cu" "F.Mask" "F.Paste")
			(net "P12V_OCP_UV_2")
		)
		(pad "D3" smd circle
			(at -0.499872 0.750062)
			(size 0.2286 0.2286)
			(layers "F.Cu" "F.Mask" "F.Paste")
			(net "P12V_OCP_OV_2")
		)
		(pad "D4" smd circle
			(at 0 0.750062)
			(size 0.2286 0.2286)
			(layers "F.Cu" "F.Mask" "F.Paste")
			(net "P12V_OCP_V3_2")
		)
		(pad "D5" smd circle
			(at 0.499872 0.750062)
			(size 0.2286 0.2286)
			(layers "F.Cu" "F.Mask" "F.Paste")
			(net "P12V_AUX")
		)
		(pad "D6" smd circle
			(at 0.999998 0.750062)
			(size 0.2286 0.2286)
			(layers "F.Cu" "F.Mask" "F.Paste")
			(net "P12V_OCP_V3_2")
		)
		(pad "D7" smd circle
			(at 1.500124 0.750062)
			(size 0.2286 0.2286)
			(layers "F.Cu" "F.Mask" "F.Paste")
			(net "P12V_OCP_PWRGD_2")
		)
	)
	(footprint ""
		(layer "F.Cu")
		(at 439.262266 -122.089926 180)
		(property "Reference" "R2404"
			(at 0 0 180)
			(layer "F.SilkS")
			(hide yes)
			(effects
				(font
					(size 1.27 1.27)
				)
			)
		)
		(property "Value" ""
			(at 0 0 180)
			(layer "F.Fab")
			(effects
				(font
					(size 1.27 1.27)
				)
			)
		)
		(duplicate_pad_numbers_are_jumpers no)
		(fp_line
			(start 0.7874 0.4064)
			(end -0.7874 0.4064)
			(stroke
				(width 0.1524)
				(type default)
			)
			(layer "F.SilkS")
		)
		(fp_line
			(start 0.7874 -0.4064)
			(end 0.7874 0.4064)
			(stroke
				(width 0.1524)
				(type default)
			)
			(layer "F.SilkS")
		)
		(fp_line
			(start -0.7874 0.4064)
			(end -0.7874 -0.4064)
			(stroke
				(width 0.1524)
				(type default)
			)
			(layer "F.SilkS")
		)
		(fp_line
			(start -0.7874 -0.4064)
			(end 0.7874 -0.4064)
			(stroke
				(width 0.1524)
				(type default)
			)
			(layer "F.SilkS")
		)
		(fp_line
			(start 0.67945 0.3048)
			(end 0.120396 0.3048)
			(stroke
				(width 0.1)
				(type default)
			)
			(layer "F.Fab")
		)
		(fp_line
			(start 0.67945 -0.3048)
			(end 0.67945 0.3048)
			(stroke
				(width 0.1)
				(type default)
			)
			(layer "F.Fab")
		)
		(fp_line
			(start 0.12065 -0.2794)
			(end 0.12065 -0.3048)
			(stroke
				(width 0.1)
				(type default)
			)
			(layer "F.Fab")
		)
		(fp_line
			(start 0.12065 -0.3048)
			(end 0.67945 -0.3048)
			(stroke
				(width 0.1)
				(type default)
			)
			(layer "F.Fab")
		)
		(fp_line
			(start 0.120396 0.3048)
			(end 0.120396 0.2794)
			(stroke
				(width 0.1)
				(type default)
			)
			(layer "F.Fab")
		)
		(fp_line
			(start 0.120396 0.2794)
			(end -0.12065 0.2794)
			(stroke
				(width 0.1)
				(type default)
			)
			(layer "F.Fab")
		)
		(fp_line
			(start -0.12065 0.3048)
			(end -0.67945 0.3048)
			(stroke
				(width 0.1)
				(type default)
			)
			(layer "F.Fab")
		)
		(fp_line
			(start -0.12065 0.2794)
			(end -0.12065 0.3048)
			(stroke
				(width 0.1)
				(type default)
			)
			(layer "F.Fab")
		)
		(fp_line
			(start -0.12065 -0.2794)
			(end 0.12065 -0.2794)
			(stroke
				(width 0.1)
				(type default)
			)
			(layer "F.Fab")
		)
		(fp_line
			(start -0.12065 -0.305054)
			(end -0.12065 -0.2794)
			(stroke
				(width 0.1)
				(type default)
			)
			(layer "F.Fab")
		)
		(fp_line
			(start -0.67945 0.3048)
			(end -0.67945 -0.305054)
			(stroke
				(width 0.1)
				(type default)
			)
			(layer "F.Fab")
		)
		(fp_line
			(start -0.67945 -0.305054)
			(end -0.12065 -0.305054)
			(stroke
				(width 0.1)
				(type default)
			)
			(layer "F.Fab")
		)
		(pad "1" smd circle
			(at -0.40005 0 180)
			(size 0 0)
			(layers "F.Cu" "F.Mask" "F.Paste")
			(net "P3V3_AUX")
		)
		(pad "2" smd circle
			(at 0.40005 0 180)
			(size 0 0)
			(layers "F.Cu" "F.Mask" "F.Paste")
			(net "IRQ_PVCCD_CPU0_VRHOT_LVC3_N")
		)
	)
	(footprint ""
		(layer "F.Cu")
		(at 32.761428 -97.554034 180)
		(property "Reference" "C2044"
			(at 0 0 180)
			(layer "F.SilkS")
			(hide yes)
			(effects
				(font
					(size 1.27 1.27)
				)
			)
		)
		(property "Value" ""
			(at 0 0 180)
			(layer "F.Fab")
			(effects
				(font
					(size 1.27 1.27)
				)
			)
		)
		(duplicate_pad_numbers_are_jumpers no)
		(fp_line
			(start 0.7874 0.4064)
			(end -0.7874 0.4064)
			(stroke
				(width 0.1524)
				(type default)
			)
			(layer "F.SilkS")
		)
		(fp_line
			(start 0.7874 -0.4064)
			(end 0.7874 0.4064)
			(stroke
				(width 0.1524)
				(type default)
			)
			(layer "F.SilkS")
		)
		(fp_line
			(start -0.7874 0.4064)
			(end -0.7874 -0.4064)
			(stroke
				(width 0.1524)
				(type default)
			)
			(layer "F.SilkS")
		)
		(fp_line
			(start -0.7874 -0.4064)
			(end 0.7874 -0.4064)
			(stroke
				(width 0.1524)
				(type default)
			)
			(layer "F.SilkS")
		)
		(fp_line
			(start 0.67945 0.3048)
			(end 0.120396 0.3048)
			(stroke
				(width 0.1)
				(type default)
			)
			(layer "F.Fab")
		)
		(fp_line
			(start 0.67945 -0.3048)
			(end 0.67945 0.3048)
			(stroke
				(width 0.1)
				(type default)
			)
			(layer "F.Fab")
		)
		(fp_line
			(start 0.12065 -0.2794)
			(end 0.12065 -0.3048)
			(stroke
				(width 0.1)
				(type default)
			)
			(layer "F.Fab")
		)
		(fp_line
			(start 0.12065 -0.3048)
			(end 0.67945 -0.3048)
			(stroke
				(width 0.1)
				(type default)
			)
			(layer "F.Fab")
		)
		(fp_line
			(start 0.120396 0.3048)
			(end 0.120396 0.2794)
			(stroke
				(width 0.1)
				(type default)
			)
			(layer "F.Fab")
		)
		(fp_line
			(start 0.120396 0.2794)
			(end -0.12065 0.2794)
			(stroke
				(width 0.1)
				(type default)
			)
			(layer "F.Fab")
		)
		(fp_line
			(start -0.12065 0.3048)
			(end -0.67945 0.3048)
			(stroke
				(width 0.1)
				(type default)
			)
			(layer "F.Fab")
		)
		(fp_line
			(start -0.12065 0.2794)
			(end -0.12065 0.3048)
			(stroke
				(width 0.1)
				(type default)
			)
			(layer "F.Fab")
		)
		(fp_line
			(start -0.12065 -0.2794)
			(end 0.12065 -0.2794)
			(stroke
				(width 0.1)
				(type default)
			)
			(layer "F.Fab")
		)
		(fp_line
			(start -0.12065 -0.305054)
			(end -0.12065 -0.2794)
			(stroke
				(width 0.1)
				(type default)
			)
			(layer "F.Fab")
		)
		(fp_line
			(start -0.67945 0.3048)
			(end -0.67945 -0.305054)
			(stroke
				(width 0.1)
				(type default)
			)
			(layer "F.Fab")
		)
		(fp_line
			(start -0.67945 -0.305054)
			(end -0.12065 -0.305054)
			(stroke
				(width 0.1)
				(type default)
			)
			(layer "F.Fab")
		)
		(pad "1" smd circle
			(at -0.40005 0 180)
			(size 0 0)
			(layers "F.Cu" "F.Mask" "F.Paste")
			(net "P5V_ADC_MAM")
		)
		(pad "2" smd circle
			(at 0.40005 0 180)
			(size 0 0)
			(layers "F.Cu" "F.Mask" "F.Paste")
			(net "GND")
		)
	)
	(footprint ""
		(layer "F.Cu")
		(at 118.849902 -410.129228)
		(property "Reference" "C1773"
			(at 0 0 0)
			(layer "F.SilkS")
			(hide yes)
			(effects
				(font
					(size 1.27 1.27)
				)
			)
		)
		(property "Value" ""
			(at 0 0 0)
			(layer "F.Fab")
			(effects
				(font
					(size 1.27 1.27)
				)
			)
		)
		(duplicate_pad_numbers_are_jumpers no)
		(fp_line
			(start -0.7874 -0.4064)
			(end 0.7874 -0.4064)
			(stroke
				(width 0.1524)
				(type default)
			)
			(layer "F.SilkS")
		)
		(fp_line
			(start -0.7874 0.4064)
			(end -0.7874 -0.4064)
			(stroke
				(width 0.1524)
				(type default)
			)
			(layer "F.SilkS")
		)
		(fp_line
			(start 0.7874 -0.4064)
			(end 0.7874 0.4064)
			(stroke
				(width 0.1524)
				(type default)
			)
			(layer "F.SilkS")
		)
		(fp_line
			(start 0.7874 0.4064)
			(end -0.7874 0.4064)
			(stroke
				(width 0.1524)
				(type default)
			)
			(layer "F.SilkS")
		)
		(fp_line
			(start -0.67945 -0.305054)
			(end -0.12065 -0.305054)
			(stroke
				(width 0.1)
				(type default)
			)
			(layer "F.Fab")
		)
		(fp_line
			(start -0.67945 0.3048)
			(end -0.67945 -0.305054)
			(stroke
				(width 0.1)
				(type default)
			)
			(layer "F.Fab")
		)
		(fp_line
			(start -0.12065 -0.305054)
			(end -0.12065 -0.2794)
			(stroke
				(width 0.1)
				(type default)
			)
			(layer "F.Fab")
		)
		(fp_line
			(start -0.12065 -0.2794)
			(end 0.12065 -0.2794)
			(stroke
				(width 0.1)
				(type default)
			)
			(layer "F.Fab")
		)
		(fp_line
			(start -0.12065 0.2794)
			(end -0.12065 0.3048)
			(stroke
				(width 0.1)
				(type default)
			)
			(layer "F.Fab")
		)
		(fp_line
			(start -0.12065 0.3048)
			(end -0.67945 0.3048)
			(stroke
				(width 0.1)
				(type default)
			)
			(layer "F.Fab")
		)
		(fp_line
			(start 0.120396 0.2794)
			(end -0.12065 0.2794)
			(stroke
				(width 0.1)
				(type default)
			)
			(layer "F.Fab")
		)
		(fp_line
			(start 0.120396 0.3048)
			(end 0.120396 0.2794)
			(stroke
				(width 0.1)
				(type default)
			)
			(layer "F.Fab")
		)
		(fp_line
			(start 0.12065 -0.3048)
			(end 0.67945 -0.3048)
			(stroke
				(width 0.1)
				(type default)
			)
			(layer "F.Fab")
		)
		(fp_line
			(start 0.12065 -0.2794)
			(end 0.12065 -0.3048)
			(stroke
				(width 0.1)
				(type default)
			)
			(layer "F.Fab")
		)
		(fp_line
			(start 0.67945 -0.3048)
			(end 0.67945 0.3048)
			(stroke
				(width 0.1)
				(type default)
			)
			(layer "F.Fab")
		)
		(fp_line
			(start 0.67945 0.3048)
			(end 0.120396 0.3048)
			(stroke
				(width 0.1)
				(type default)
			)
			(layer "F.Fab")
		)
		(pad "1" smd circle
			(at -0.40005 0)
			(size 0 0)
			(layers "F.Cu" "F.Mask" "F.Paste")
			(net "BIC_MONITER_ISO")
		)
		(pad "2" smd circle
			(at 0.40005 0)
			(size 0 0)
			(layers "F.Cu" "F.Mask" "F.Paste")
			(net "GND")
		)
	)
	(footprint ""
		(layer "F.Cu")
		(at 365.844328 -336.192368 90)
		(property "Reference" "PC270"
			(at 0 0 90)
			(layer "F.SilkS")
			(hide yes)
			(effects
				(font
					(size 1.27 1.27)
				)
			)
		)
		(property "Value" ""
			(at 0 0 90)
			(layer "F.Fab")
			(effects
				(font
					(size 1.27 1.27)
				)
			)
		)
		(duplicate_pad_numbers_are_jumpers no)
		(fp_line
			(start 0.7874 -0.4064)
			(end 0.7874 0.4064)
			(stroke
				(width 0.1524)
				(type default)
			)
			(layer "F.SilkS")
		)
		(fp_line
			(start -0.7874 -0.4064)
			(end 0.7874 -0.4064)
			(stroke
				(width 0.1524)
				(type default)
			)
			(layer "F.SilkS")
		)
		(fp_line
			(start 0.7874 0.4064)
			(end -0.7874 0.4064)
			(stroke
				(width 0.1524)
				(type default)
			)
			(layer "F.SilkS")
		)
		(fp_line
			(start -0.7874 0.4064)
			(end -0.7874 -0.4064)
			(stroke
				(width 0.1524)
				(type default)
			)
			(layer "F.SilkS")
		)
		(fp_line
			(start -0.12065 -0.305054)
			(end -0.12065 -0.2794)
			(stroke
				(width 0.1)
				(type default)
			)
			(layer "F.Fab")
		)
		(fp_line
			(start -0.67945 -0.305054)
			(end -0.12065 -0.305054)
			(stroke
				(width 0.1)
				(type default)
			)
			(layer "F.Fab")
		)
		(fp_line
			(start 0.67945 -0.3048)
			(end 0.67945 0.3048)
			(stroke
				(width 0.1)
				(type default)
			)
			(layer "F.Fab")
		)
		(fp_line
			(start 0.12065 -0.3048)
			(end 0.67945 -0.3048)
			(stroke
				(width 0.1)
				(type default)
			)
			(layer "F.Fab")
		)
		(fp_line
			(start 0.12065 -0.2794)
			(end 0.12065 -0.3048)
			(stroke
				(width 0.1)
				(type default)
			)
			(layer "F.Fab")
		)
		(fp_line
			(start -0.12065 -0.2794)
			(end 0.12065 -0.2794)
			(stroke
				(width 0.1)
				(type default)
			)
			(layer "F.Fab")
		)
		(fp_line
			(start 0.120396 0.2794)
			(end -0.12065 0.2794)
			(stroke
				(width 0.1)
				(type default)
			)
			(layer "F.Fab")
		)
		(fp_line
			(start -0.12065 0.2794)
			(end -0.12065 0.3048)
			(stroke
				(width 0.1)
				(type default)
			)
			(layer "F.Fab")
		)
		(fp_line
			(start 0.67945 0.3048)
			(end 0.120396 0.3048)
			(stroke
				(width 0.1)
				(type default)
			)
			(layer "F.Fab")
		)
		(fp_line
			(start 0.120396 0.3048)
			(end 0.120396 0.2794)
			(stroke
				(width 0.1)
				(type default)
			)
			(layer "F.Fab")
		)
		(fp_line
			(start -0.12065 0.3048)
			(end -0.67945 0.3048)
			(stroke
				(width 0.1)
				(type default)
			)
			(layer "F.Fab")
		)
		(fp_line
			(start -0.67945 0.3048)
			(end -0.67945 -0.305054)
			(stroke
				(width 0.1)
				(type default)
			)
			(layer "F.Fab")
		)
		(pad "1" smd circle
			(at -0.40005 0 90)
			(size 0 0)
			(layers "F.Cu" "F.Mask" "F.Paste")
			(net "PVCCIN_CPU0_VDD4")
		)
		(pad "2" smd circle
			(at 0.40005 0 90)
			(size 0 0)
			(layers "F.Cu" "F.Mask" "F.Paste")
			(net "GND")
		)
	)
)
